(kicad_pcb
	(version 20260206)
	(generator "pcbnew")
	(generator_version "10.0")
	(general
		(thickness 1.6)
		(legacy_teardrops no)
	)
	(paper "A4")
	(title_block
		(title "v2-pdb — ms_pdb_v2.brd")
		(comment 1 "Open CloudServer (Microsoft) / footprints 6-7 of 348")
	)
	(layers
		(0 "F.Cu" signal "TOP")
		(4 "In1.Cu" signal "GND")
		(6 "In2.Cu" signal "IN1")
		(8 "In3.Cu" signal "VCC")
		(10 "In4.Cu" signal "VCC1")
		(12 "In5.Cu" signal "IN2")
		(14 "In6.Cu" signal "GND1")
		(2 "B.Cu" signal "BOTTOM")
		(9 "F.Adhes" user "F.Adhesive")
		(11 "B.Adhes" user "B.Adhesive")
		(13 "F.Paste" user "Package Geometry/Pastemask Top")
		(15 "B.Paste" user "Package Geometry/Pastemask Bottom")
		(5 "F.SilkS" user "Ref Des/Silkscreen Top")
		(7 "B.SilkS" user "Ref Des/Silkscreen Bottom")
		(1 "F.Mask" user "Board Geometry/Soldermask Top")
		(3 "B.Mask" user "Board Geometry/Soldermask Bottom")
		(17 "Dwgs.User" user "User.Drawings")
		(19 "Cmts.User" user "User.Comments")
		(21 "Eco1.User" user "User.Eco1")
		(23 "Eco2.User" user "User.Eco2")
		(25 "Edge.Cuts" user "Board Geometry/Outline")
		(27 "Margin" user)
		(31 "F.CrtYd" user "Package Geometry/Place Bound Top")
		(29 "B.CrtYd" user "Package Geometry/Place Bound Bottom")
		(35 "F.Fab" user "Ref Des/Assembly Top")
		(33 "B.Fab" user "Ref Des/Assembly Bottom")
	)
	(footprint ""
		(layer "F.Cu")
		(at 30.45968 -348.52991)
		(property "Reference" "J4"
			(at 7.95274 12.227052 0)
			(unlocked yes)
			(layer "F.SilkS")
			(effects
				(font
					(size 0.7874 0.5842)
					(thickness 0.1524)
				)
				(justify left)
			)
		)
		(property "Value" ""
			(at 0 0 0)
			(layer "F.Fab")
			(effects
				(font
					(size 1.27 1.27)
				)
			)
		)
		(duplicate_pad_numbers_are_jumpers no)
		(fp_line
			(start -2.135124 -4.560062)
			(end -2.135124 83.300062)
			(stroke
				(width 0.1524)
				(type default)
			)
			(layer "F.SilkS")
		)
		(fp_line
			(start -2.135124 83.300062)
			(end 7.215124 83.300062)
			(stroke
				(width 0.1524)
				(type default)
			)
			(layer "F.SilkS")
		)
		(fp_line
			(start 7.215124 -4.560062)
			(end -2.135124 -4.560062)
			(stroke
				(width 0.1524)
				(type default)
			)
			(layer "F.SilkS")
		)
		(fp_line
			(start 7.215124 83.300062)
			(end 7.215124 -4.560062)
			(stroke
				(width 0.1524)
				(type default)
			)
			(layer "F.SilkS")
		)
		(fp_poly
			(pts
				(xy -2.422398 -0.000762) (xy -5.122418 -0.700786) (xy -5.122418 0.699262)
			)
			(stroke
				(width 0)
				(type default)
			)
			(fill yes)
			(layer "F.SilkS")
		)
		(fp_poly
			(pts
				(xy -2.28219 -0.127) (xy -4.98221 -0.827024) (xy -4.98221 0.573024)
			)
			(stroke
				(width 0)
				(type default)
			)
			(fill yes)
			(layer "B.SilkS")
		)
		(fp_poly
			(pts
				(xy -0.8636 -0.8636) (xy -0.8636 79.6036) (xy -0.8636 79.629) (xy 5.9436 79.629) (xy 5.9436 79.6036)
				(xy 5.9436 -0.8636) (xy 5.9436 -0.889) (xy -0.8636 -0.889)
			)
			(stroke
				(width 0)
				(type default)
			)
			(fill no)
			(layer "B.CrtYd")
		)
		(fp_rect
			(start -2.135124 -4.560062)
			(end 7.21487 83.300062)
			(stroke
				(width 0)
				(type default)
			)
			(fill no)
			(layer "F.CrtYd")
		)
		(fp_line
			(start -2.135124 -4.560062)
			(end 7.215124 -4.560062)
			(stroke
				(width 0.1)
				(type default)
			)
			(layer "F.Fab")
		)
		(fp_line
			(start -2.135124 83.300062)
			(end -2.135124 -4.560062)
			(stroke
				(width 0.1)
				(type default)
			)
			(layer "F.Fab")
		)
		(fp_line
			(start 7.215124 -4.560062)
			(end 7.215124 83.300062)
			(stroke
				(width 0.1)
				(type default)
			)
			(layer "F.Fab")
		)
		(fp_line
			(start 7.215124 83.300062)
			(end -2.135124 83.300062)
			(stroke
				(width 0.1)
				(type default)
			)
			(layer "F.Fab")
		)
		(fp_text user "32"
			(at -3.83159 78.970124 0)
			(unlocked yes)
			(layer "F.SilkS")
			(effects
				(font
					(size 0.7874 0.5842)
					(thickness 0.1524)
				)
				(justify left)
			)
		)
		(fp_text user "1"
			(at -3.299206 -1.063752 0)
			(unlocked yes)
			(layer "F.SilkS")
			(effects
				(font
					(size 0.7874 0.5842)
					(thickness 0.1524)
				)
				(justify left)
			)
		)
		(fp_text user "33"
			(at 7.548626 82.342482 0)
			(unlocked yes)
			(layer "F.SilkS")
			(effects
				(font
					(size 0.7874 0.5842)
					(thickness 0.1524)
				)
				(justify left)
			)
		)
		(fp_text user "64"
			(at 7.602728 -0.1905 0)
			(unlocked yes)
			(layer "F.SilkS")
			(effects
				(font
					(size 0.7874 0.5842)
					(thickness 0.1524)
				)
				(justify left)
			)
		)
		(fp_text user "1"
			(at -1.714246 -0.92456 0)
			(unlocked yes)
			(layer "B.SilkS")
			(effects
				(font
					(size 0.7874 0.5842)
					(thickness 0.1524)
				)
				(justify left mirror)
			)
		)
		(fp_text user "32"
			(at -0.789432 79.774796 0)
			(unlocked yes)
			(layer "B.SilkS")
			(effects
				(font
					(size 0.7874 0.5842)
					(thickness 0.1524)
				)
				(justify left mirror)
			)
		)
		(fp_text user "64"
			(at 5.867146 -1.71323 0)
			(unlocked yes)
			(layer "B.SilkS")
			(effects
				(font
					(size 0.7874 0.5842)
					(thickness 0.1524)
				)
				(justify left mirror)
			)
		)
		(fp_text user "33"
			(at 5.969508 82.246216 0)
			(unlocked yes)
			(layer "B.SilkS")
			(effects
				(font
					(size 0.7874 0.5842)
					(thickness 0.1524)
				)
				(justify left mirror)
			)
		)
		(pad "1" thru_hole rect
			(at 0 0 270)
			(size 1.6256 1.6256)
			(drill 1.1176)
			(layers "*.Cu" "*.Mask")
			(remove_unused_layers no)
			(net "P12V")
			(clearance 0)
			(padstack
				(mode front_inner_back)
				(layer "Inner"
					(shape circle)
					(size 1.6256 1.6256)
					(clearance 0)
				)
				(layer "B.Cu"
					(shape rect)
					(size 1.6256 1.6256)
					(clearance 0)
				)
			)
		)
		(pad "2" thru_hole circle
			(at 0 2.54 270)
			(size 1.6256 1.6256)
			(drill 1.1176)
			(layers "*.Cu" "*.Mask")
			(remove_unused_layers no)
			(net "P12V")
			(clearance 0)
		)
		(pad "3" thru_hole circle
			(at 0 5.08 270)
			(size 1.6256 1.6256)
			(drill 1.1176)
			(layers "*.Cu" "*.Mask")
			(remove_unused_layers no)
			(net "P12V")
			(clearance 0)
		)
		(pad "4" thru_hole circle
			(at 0 7.62 270)
			(size 1.6256 1.6256)
			(drill 1.1176)
			(layers "*.Cu" "*.Mask")
			(remove_unused_layers no)
			(net "P12V")
			(clearance 0)
		)
		(pad "5" thru_hole circle
			(at 0 10.16 270)
			(size 1.6256 1.6256)
			(drill 1.1176)
			(layers "*.Cu" "*.Mask")
			(remove_unused_layers no)
			(net "P12V")
			(clearance 0)
		)
		(pad "6" thru_hole circle
			(at 0 12.7 270)
			(size 1.6256 1.6256)
			(drill 1.1176)
			(layers "*.Cu" "*.Mask")
			(remove_unused_layers no)
			(net "P12V")
			(clearance 0)
		)
		(pad "7" thru_hole circle
			(at 0 15.24 270)
			(size 1.6256 1.6256)
			(drill 1.1176)
			(layers "*.Cu" "*.Mask")
			(remove_unused_layers no)
			(net "P12V")
			(clearance 0)
		)
		(pad "8" thru_hole circle
			(at 0 17.78 270)
			(size 1.6256 1.6256)
			(drill 1.1176)
			(layers "*.Cu" "*.Mask")
			(remove_unused_layers no)
			(net "P12V")
			(clearance 0)
		)
		(pad "9" thru_hole circle
			(at 0 20.32 270)
			(size 1.6256 1.6256)
			(drill 1.1176)
			(layers "*.Cu" "*.Mask")
			(remove_unused_layers no)
			(net "P12V")
			(clearance 0)
		)
		(pad "10" thru_hole circle
			(at 0 22.86 270)
			(size 1.6256 1.6256)
			(drill 1.1176)
			(layers "*.Cu" "*.Mask")
			(remove_unused_layers no)
			(net "P12V")
			(clearance 0)
		)
		(pad "11" thru_hole circle
			(at 0 25.4 270)
			(size 1.6256 1.6256)
			(drill 1.1176)
			(layers "*.Cu" "*.Mask")
			(remove_unused_layers no)
			(net "P12V")
			(clearance 0)
		)
		(pad "12" thru_hole circle
			(at 0 27.94 270)
			(size 1.6256 1.6256)
			(drill 1.1176)
			(layers "*.Cu" "*.Mask")
			(remove_unused_layers no)
			(net "P12V")
			(clearance 0)
		)
		(pad "13" thru_hole circle
			(at 0 30.48 270)
			(size 1.6256 1.6256)
			(drill 1.1176)
			(layers "*.Cu" "*.Mask")
			(remove_unused_layers no)
			(net "GND")
			(clearance 0)
		)
		(pad "14" thru_hole circle
			(at 0 33.02 270)
			(size 1.6256 1.6256)
			(drill 1.1176)
			(layers "*.Cu" "*.Mask")
			(remove_unused_layers no)
			(net "GND")
			(clearance 0)
		)
		(pad "15" thru_hole circle
			(at 0 35.56 270)
			(size 1.6256 1.6256)
			(drill 1.1176)
			(layers "*.Cu" "*.Mask")
			(remove_unused_layers no)
			(net "GND")
			(clearance 0)
		)
		(pad "16" thru_hole circle
			(at 0 38.1 270)
			(size 1.6256 1.6256)
			(drill 1.1176)
			(layers "*.Cu" "*.Mask")
			(remove_unused_layers no)
			(net "GND")
			(clearance 0)
		)
		(pad "17" thru_hole circle
			(at 0 40.64 270)
			(size 1.6256 1.6256)
			(drill 1.1176)
			(layers "*.Cu" "*.Mask")
			(remove_unused_layers no)
			(net "GND")
			(clearance 0)
		)
		(pad "18" thru_hole circle
			(at 0 43.18 270)
			(size 1.6256 1.6256)
			(drill 1.1176)
			(layers "*.Cu" "*.Mask")
			(remove_unused_layers no)
			(net "GND")
			(clearance 0)
		)
		(pad "19" thru_hole circle
			(at 0 45.72 270)
			(size 1.6256 1.6256)
			(drill 1.1176)
			(layers "*.Cu" "*.Mask")
			(remove_unused_layers no)
			(net "GND")
			(clearance 0)
		)
		(pad "20" thru_hole circle
			(at 0 48.26 270)
			(size 1.6256 1.6256)
			(drill 1.1176)
			(layers "*.Cu" "*.Mask")
			(remove_unused_layers no)
			(net "GND")
			(clearance 0)
		)
		(pad "21" thru_hole circle
			(at 0 50.8 270)
			(size 1.6256 1.6256)
			(drill 1.1176)
			(layers "*.Cu" "*.Mask")
			(remove_unused_layers no)
			(net "GND")
			(clearance 0)
		)
		(pad "22" thru_hole circle
			(at 0 53.34 270)
			(size 1.6256 1.6256)
			(drill 1.1176)
			(layers "*.Cu" "*.Mask")
			(remove_unused_layers no)
			(net "GND")
			(clearance 0)
		)
		(pad "23" thru_hole circle
			(at 0 55.88 270)
			(size 1.6256 1.6256)
			(drill 1.1176)
			(layers "*.Cu" "*.Mask")
			(remove_unused_layers no)
			(net "GND")
			(clearance 0)
		)
		(pad "24" thru_hole circle
			(at 0 58.42 270)
			(size 1.6256 1.6256)
			(drill 1.1176)
			(layers "*.Cu" "*.Mask")
			(remove_unused_layers no)
			(net "GND")
			(clearance 0)
		)
		(pad "25" thru_hole circle
			(at 0 60.96 270)
			(size 1.6256 1.6256)
			(drill 1.1176)
			(layers "*.Cu" "*.Mask")
			(remove_unused_layers no)
			(net "PHLOSS")
			(clearance 0)
		)
		(pad "26" thru_hole circle
			(at 0 63.5 270)
			(size 1.6256 1.6256)
			(drill 1.1176)
			(layers "*.Cu" "*.Mask")
			(remove_unused_layers no)
			(net "PSU4_REMOTE_N")
			(clearance 0)
		)
		(pad "27" thru_hole circle
			(at 0 66.04 270)
			(size 1.6256 1.6256)
			(drill 1.1176)
			(layers "*.Cu" "*.Mask")
			(remove_unused_layers no)
			(net "PSU4_AC_OK")
			(clearance 0)
		)
		(pad "28" thru_hole circle
			(at 0 68.58 270)
			(size 1.6256 1.6256)
			(drill 1.1176)
			(layers "*.Cu" "*.Mask")
			(remove_unused_layers no)
			(net "PSU4_CSAHRE")
			(clearance 0)
		)
		(pad "29" thru_hole circle
			(at 0 71.12 270)
			(size 1.6256 1.6256)
			(drill 1.1176)
			(layers "*.Cu" "*.Mask")
			(remove_unused_layers no)
			(net "PSU4_PS_ON_N")
			(clearance 0)
		)
		(pad "30" thru_hole circle
			(at 0 73.66 270)
			(size 1.6256 1.6256)
			(drill 1.1176)
			(layers "*.Cu" "*.Mask")
			(remove_unused_layers no)
			(net "PSU4_PS_KILL")
			(clearance 0)
		)
		(pad "31" thru_hole circle
			(at 0 76.2 270)
			(size 1.6256 1.6256)
			(drill 1.1176)
			(layers "*.Cu" "*.Mask")
			(remove_unused_layers no)
			(net "PSU4_RESET")
			(clearance 0)
		)
		(pad "32" thru_hole circle
			(at 0 78.74 270)
			(size 1.6256 1.6256)
			(drill 1.1176)
			(layers "*.Cu" "*.Mask")
			(remove_unused_layers no)
			(net "PSU_ALERT_N")
			(clearance 0)
		)
		(pad "33" thru_hole circle
			(at 5.08 78.74 270)
			(size 1.6256 1.6256)
			(drill 1.1176)
			(layers "*.Cu" "*.Mask")
			(remove_unused_layers no)
			(net "I2C_PSU2_SDA")
			(clearance 0)
		)
		(pad "34" thru_hole circle
			(at 5.08 76.2 270)
			(size 1.6256 1.6256)
			(drill 1.1176)
			(layers "*.Cu" "*.Mask")
			(remove_unused_layers no)
			(net "Net_427")
			(clearance 0)
		)
		(pad "35" thru_hole circle
			(at 5.08 73.66 270)
			(size 1.6256 1.6256)
			(drill 1.1176)
			(layers "*.Cu" "*.Mask")
			(remove_unused_layers no)
			(net "I2C_PSU2_SCL")
			(clearance 0)
		)
		(pad "36" thru_hole circle
			(at 5.08 71.12 270)
			(size 1.6256 1.6256)
			(drill 1.1176)
			(layers "*.Cu" "*.Mask")
			(remove_unused_layers no)
			(net "PSU4_RETURN")
			(clearance 0)
		)
		(pad "37" thru_hole circle
			(at 5.08 68.58 270)
			(size 1.6256 1.6256)
			(drill 1.1176)
			(layers "*.Cu" "*.Mask")
			(remove_unused_layers no)
			(net "PSU4_DC_OK")
			(clearance 0)
		)
		(pad "38" thru_hole circle
			(at 5.08 66.04 270)
			(size 1.6256 1.6256)
			(drill 1.1176)
			(layers "*.Cu" "*.Mask")
			(remove_unused_layers no)
			(net "PSU4_AD0")
			(clearance 0)
		)
		(pad "39" thru_hole circle
			(at 5.08 63.5 270)
			(size 1.6256 1.6256)
			(drill 1.1176)
			(layers "*.Cu" "*.Mask")
			(remove_unused_layers no)
			(net "P12V_STBY")
			(clearance 0)
		)
		(pad "40" thru_hole circle
			(at 5.08 60.96 270)
			(size 1.6256 1.6256)
			(drill 1.1176)
			(layers "*.Cu" "*.Mask")
			(remove_unused_layers no)
			(net "PSU4_REMOTE_P")
			(clearance 0)
		)
		(pad "41" thru_hole circle
			(at 5.08 58.42 270)
			(size 1.6256 1.6256)
			(drill 1.1176)
			(layers "*.Cu" "*.Mask")
			(remove_unused_layers no)
			(net "GND")
			(clearance 0)
		)
		(pad "42" thru_hole circle
			(at 5.08 55.88 270)
			(size 1.6256 1.6256)
			(drill 1.1176)
			(layers "*.Cu" "*.Mask")
			(remove_unused_layers no)
			(net "GND")
			(clearance 0)
		)
		(pad "43" thru_hole circle
			(at 5.08 53.34 270)
			(size 1.6256 1.6256)
			(drill 1.1176)
			(layers "*.Cu" "*.Mask")
			(remove_unused_layers no)
			(net "GND")
			(clearance 0)
		)
		(pad "44" thru_hole circle
			(at 5.08 50.8 270)
			(size 1.6256 1.6256)
			(drill 1.1176)
			(layers "*.Cu" "*.Mask")
			(remove_unused_layers no)
			(net "GND")
			(clearance 0)
		)
		(pad "45" thru_hole circle
			(at 5.08 48.26 270)
			(size 1.6256 1.6256)
			(drill 1.1176)
			(layers "*.Cu" "*.Mask")
			(remove_unused_layers no)
			(net "GND")
			(clearance 0)
		)
		(pad "46" thru_hole circle
			(at 5.08 45.72 270)
			(size 1.6256 1.6256)
			(drill 1.1176)
			(layers "*.Cu" "*.Mask")
			(remove_unused_layers no)
			(net "GND")
			(clearance 0)
		)
		(pad "47" thru_hole circle
			(at 5.08 43.18 270)
			(size 1.6256 1.6256)
			(drill 1.1176)
			(layers "*.Cu" "*.Mask")
			(remove_unused_layers no)
			(net "GND")
			(clearance 0)
		)
		(pad "48" thru_hole circle
			(at 5.08 40.64 270)
			(size 1.6256 1.6256)
			(drill 1.1176)
			(layers "*.Cu" "*.Mask")
			(remove_unused_layers no)
			(net "GND")
			(clearance 0)
		)
		(pad "49" thru_hole circle
			(at 5.08 38.1 270)
			(size 1.6256 1.6256)
			(drill 1.1176)
			(layers "*.Cu" "*.Mask")
			(remove_unused_layers no)
			(net "GND")
			(clearance 0)
		)
		(pad "50" thru_hole circle
			(at 5.08 35.56 270)
			(size 1.6256 1.6256)
			(drill 1.1176)
			(layers "*.Cu" "*.Mask")
			(remove_unused_layers no)
			(net "GND")
			(clearance 0)
		)
		(pad "51" thru_hole circle
			(at 5.08 33.02 270)
			(size 1.6256 1.6256)
			(drill 1.1176)
			(layers "*.Cu" "*.Mask")
			(remove_unused_layers no)
			(net "GND")
			(clearance 0)
		)
		(pad "52" thru_hole circle
			(at 5.08 30.48 270)
			(size 1.6256 1.6256)
			(drill 1.1176)
			(layers "*.Cu" "*.Mask")
			(remove_unused_layers no)
			(net "GND")
			(clearance 0)
		)
		(pad "53" thru_hole circle
			(at 5.08 27.94 270)
			(size 1.6256 1.6256)
			(drill 1.1176)
			(layers "*.Cu" "*.Mask")
			(remove_unused_layers no)
			(net "P12V")
			(clearance 0)
		)
		(pad "54" thru_hole circle
			(at 5.08 25.4 270)
			(size 1.6256 1.6256)
			(drill 1.1176)
			(layers "*.Cu" "*.Mask")
			(remove_unused_layers no)
			(net "P12V")
			(clearance 0)
		)
		(pad "55" thru_hole circle
			(at 5.08 22.86 270)
			(size 1.6256 1.6256)
			(drill 1.1176)
			(layers "*.Cu" "*.Mask")
			(remove_unused_layers no)
			(net "P12V")
			(clearance 0)
		)
		(pad "56" thru_hole circle
			(at 5.08 20.32 270)
			(size 1.6256 1.6256)
			(drill 1.1176)
			(layers "*.Cu" "*.Mask")
			(remove_unused_layers no)
			(net "P12V")
			(clearance 0)
		)
		(pad "57" thru_hole circle
			(at 5.08 17.78 270)
			(size 1.6256 1.6256)
			(drill 1.1176)
			(layers "*.Cu" "*.Mask")
			(remove_unused_layers no)
			(net "P12V")
			(clearance 0)
		)
		(pad "58" thru_hole circle
			(at 5.08 15.24 270)
			(size 1.6256 1.6256)
			(drill 1.1176)
			(layers "*.Cu" "*.Mask")
			(remove_unused_layers no)
			(net "P12V")
			(clearance 0)
		)
		(pad "59" thru_hole circle
			(at 5.08 12.7 270)
			(size 1.6256 1.6256)
			(drill 1.1176)
			(layers "*.Cu" "*.Mask")
			(remove_unused_layers no)
			(net "P12V")
			(clearance 0)
		)
		(pad "60" thru_hole circle
			(at 5.08 10.16 270)
			(size 1.6256 1.6256)
			(drill 1.1176)
			(layers "*.Cu" "*.Mask")
			(remove_unused_layers no)
			(net "P12V")
			(clearance 0)
		)
		(pad "61" thru_hole circle
			(at 5.08 7.62 270)
			(size 1.6256 1.6256)
			(drill 1.1176)
			(layers "*.Cu" "*.Mask")
			(remove_unused_layers no)
			(net "P12V")
			(clearance 0)
		)
		(pad "62" thru_hole circle
			(at 5.08 5.08 270)
			(size 1.6256 1.6256)
			(drill 1.1176)
			(layers "*.Cu" "*.Mask")
			(remove_unused_layers no)
			(net "P12V")
			(clearance 0)
		)
		(pad "63" thru_hole circle
			(at 5.08 2.54 270)
			(size 1.6256 1.6256)
			(drill 1.1176)
			(layers "*.Cu" "*.Mask")
			(remove_unused_layers no)
			(net "P12V")
			(clearance 0)
		)
		(pad "64" thru_hole circle
			(at 5.08 0 270)
			(size 1.6256 1.6256)
			(drill 1.1176)
			(layers "*.Cu" "*.Mask")
			(remove_unused_layers no)
			(net "P12V")
			(clearance 0)
		)
	)
	(footprint ""
		(layer "F.Cu")
		(at 26.928318 -196.6214)
		(property "Reference" "R6"
			(at -3.177032 0.103886 0)
			(unlocked yes)
			(layer "F.SilkS")
			(effects
				(font
					(size 0.7874 0.5842)
					(thickness 0.1524)
				)
				(justify left)
			)
		)
		(property "Value" ""
			(at 0 0 0)
			(layer "F.Fab")
			(effects
				(font
					(size 1.27 1.27)
				)
			)
		)
		(duplicate_pad_numbers_are_jumpers no)
		(fp_line
			(start -0.7874 -0.4064)
			(end 0.7874 -0.4064)
			(stroke
				(width 0.1524)
				(type default)
			)
			(layer "F.SilkS")
		)
		(fp_line
			(start -0.7874 0.4064)
			(end -0.7874 -0.4064)
			(stroke
				(width 0.1524)
				(type default)
			)
			(layer "F.SilkS")
		)
		(fp_line
			(start 0.7874 -0.4064)
			(end 0.7874 0.4064)
			(stroke
				(width 0.1524)
				(type default)
			)
			(layer "F.SilkS")
		)
		(fp_line
			(start 0.7874 0.4064)
			(end -0.7874 0.4064)
			(stroke
				(width 0.1524)
				(type default)
			)
			(layer "F.SilkS")
		)
		(fp_poly
			(pts
				(xy -0.508 0.2794) (xy -0.508 0.2286) (xy -0.635 0.2286) (xy -0.635 -0.254) (xy -0.5334 -0.254)
				(xy -0.5334 -0.2794) (xy 0.5334 -0.2794) (xy 0.5334 -0.254) (xy 0.635 -0.254) (xy 0.635 0.254) (xy 0.5334 0.254)
				(xy 0.5334 0.2794)
			)
			(stroke
				(width 0)
				(type default)
			)
			(fill no)
			(layer "F.CrtYd")
		)
		(pad "1" smd rect
			(at 0.40005 0)
			(size 0.4572 0.508)
			(layers "F.Cu" "F.Mask" "F.Paste")
			(net "PSU3_REMOTE_N")
		)
		(pad "2" smd rect
			(at -0.40005 0)
			(size 0.4572 0.508)
			(layers "F.Cu" "F.Mask" "F.Paste")
			(net "GND")
		)
	)
)
